(kicad_pcb
	(version 20260206)
	(generator "pcbnew")
	(generator_version "10.0")
	(general
		(thickness 1.6)
		(legacy_teardrops no)
	)
	(paper "A4")
	(title_block
		(title "03242023_DA0F0TMBIJ0_F0T_Motherboard_J_brd_V01_OCP.brd")
		(comment 1 "Grand Teton / footprint 1682 of 6105 (U1), pads 957-1061 of 4677")
	)
	(layers
		(0 "F.Cu" signal "TOP")
		(4 "In1.Cu" signal "GND")
		(6 "In2.Cu" signal "IN1")
		(8 "In3.Cu" signal "GND1")
		(10 "In4.Cu" signal "IN2")
		(12 "In5.Cu" signal "GND2")
		(14 "In6.Cu" signal "IN3")
		(16 "In7.Cu" signal "GND3")
		(18 "In8.Cu" signal "VCC")
		(20 "In9.Cu" signal "VCC1")
		(22 "In10.Cu" signal "GND4")
		(24 "In11.Cu" signal "IN4")
		(26 "In12.Cu" signal "GND5")
		(28 "In13.Cu" signal "IN5")
		(30 "In14.Cu" signal "GND6")
		(32 "In15.Cu" signal "IN6")
		(34 "In16.Cu" signal "GND7")
		(2 "B.Cu" signal "BOTTOM")
		(9 "F.Adhes" user "F.Adhesive")
		(11 "B.Adhes" user "B.Adhesive")
		(13 "F.Paste" user "Package Geometry/Pastemask Top")
		(15 "B.Paste" user "Package Geometry/Pastemask Bottom")
		(5 "F.SilkS" user "Ref Des/Silkscreen Top")
		(7 "B.SilkS" user "Ref Des/Silkscreen Bottom")
		(1 "F.Mask" user "Board Geometry/Soldermask Top")
		(3 "B.Mask" user "Board Geometry/Soldermask Bottom")
		(17 "Dwgs.User" user "User.Drawings")
		(19 "Cmts.User" user "User.Comments")
		(21 "Eco1.User" user "User.Eco1")
		(23 "Eco2.User" user "User.Eco2")
		(25 "Edge.Cuts" user "Board Geometry/Outline")
		(27 "Margin" user)
		(31 "F.CrtYd" user "Package Geometry/Place Bound Top")
		(29 "B.CrtYd" user "Package Geometry/Place Bound Bottom")
		(35 "F.Fab" user "Ref Des/Assembly Top")
		(33 "B.Fab" user "Ref Des/Assembly Bottom")
	)
	(footprint ""
		(layer "F.Cu")
		(at 111.93018 -251.76988 90)
		(property "Reference" "U1"
			(at -74.913236 41.548812 0)
			(unlocked yes)
			(layer "F.SilkS")
			(effects
				(font
					(size 1.6002 1.1938)
					(thickness 0.1524)
				)
				(justify left)
			)
		)
		(property "Value" ""
			(at 0 0 90)
			(layer "F.Fab")
			(effects
				(font
					(size 1.27 1.27)
				)
			)
		)
		(duplicate_pad_numbers_are_jumpers no)
		(pad "BA78" smd circle
			(at 26.844498 -8.168132 270)
			(size 0.4318 0.4318)
			(layers "F.Cu" "F.Mask" "F.Paste")
			(net "UPI_CPU1_CPU0_P2P2_DP<10>")
		)
		(pad "BA80" smd circle
			(at 28.472384 -8.168132 270)
			(size 0.4318 0.4318)
			(layers "F.Cu" "F.Mask" "F.Paste")
			(net "UPI_CPU1_CPU0_P2P2_DN<17>")
		)
		(pad "BA82" smd circle
			(at 30.100016 -8.168132 270)
			(size 0.4318 0.4318)
			(layers "F.Cu" "F.Mask" "F.Paste")
			(net "UPI_CPU1_CPU0_P2P2_DP<18>")
		)
		(pad "BA84" smd circle
			(at 31.727902 -8.168132 270)
			(size 0.4318 0.4318)
			(layers "F.Cu" "F.Mask" "F.Paste")
			(net "GND")
		)
		(pad "BA86" smd circle
			(at 33.355534 -8.168132 270)
			(size 0.4318 0.4318)
			(layers "F.Cu" "F.Mask" "F.Paste")
			(net "P5E_CPU1_PE4_TX_DN<15>")
		)
		(pad "BA88" smd circle
			(at 34.98342 -8.168132 270)
			(size 0.4318 0.4318)
			(layers "F.Cu" "F.Mask" "F.Paste")
			(net "GND")
		)
		(pad "BA90" smd circle
			(at 36.611306 -8.168132 270)
			(size 0.4318 0.4318)
			(layers "F.Cu" "F.Mask" "F.Paste")
			(net "P5E_CPU1_PE4_RX_DP<15>")
		)
		(pad "BB2" smd circle
			(at -36.611306 -7.808468 270)
			(size 0.4318 0.4318)
			(layers "F.Cu" "F.Mask" "F.Paste")
			(net "UPI_CPU1_CPU0_P0P1_DN<16>")
		)
		(pad "BB4" smd circle
			(at -34.98342 -7.808468 270)
			(size 0.4318 0.4318)
			(layers "F.Cu" "F.Mask" "F.Paste")
			(net "GND")
		)
		(pad "BB6" smd circle
			(at -33.355534 -7.808468 270)
			(size 0.4318 0.4318)
			(layers "F.Cu" "F.Mask" "F.Paste")
			(net "UPI_CPU0_CPU1_P1P0_DN<16>")
		)
		(pad "BB8" smd circle
			(at -31.727902 -7.808468 270)
			(size 0.4318 0.4318)
			(layers "F.Cu" "F.Mask" "F.Paste")
			(net "GND")
		)
		(pad "BB10" smd circle
			(at -30.100016 -7.808468 270)
			(size 0.4318 0.4318)
			(layers "F.Cu" "F.Mask" "F.Paste")
			(net "GND")
		)
		(pad "BB12" smd circle
			(at -28.472384 -7.808468 270)
			(size 0.4318 0.4318)
			(layers "F.Cu" "F.Mask" "F.Paste")
			(net "GND")
		)
		(pad "BB14" smd circle
			(at -26.844498 -7.808468 270)
			(size 0.4318 0.4318)
			(layers "F.Cu" "F.Mask" "F.Paste")
			(net "P5E_CPU1_PE0_TX_DN<15>")
		)
		(pad "BB16" smd circle
			(at -25.216612 -7.808468 270)
			(size 0.4318 0.4318)
			(layers "F.Cu" "F.Mask" "F.Paste")
			(net "GND")
		)
		(pad "BB18" smd circle
			(at -23.58898 -7.808468 270)
			(size 0.4318 0.4318)
			(layers "F.Cu" "F.Mask" "F.Paste")
			(net "TP_DMI_CPU1_PCH_RX_C_DN<0>")
		)
		(pad "BB20" smd circle
			(at -21.961094 -7.808468 270)
			(size 0.4318 0.4318)
			(layers "F.Cu" "F.Mask" "F.Paste")
			(net "GND")
		)
		(pad "BB22" smd circle
			(at -20.333462 -7.808468 270)
			(size 0.4318 0.4318)
			(layers "F.Cu" "F.Mask" "F.Paste")
			(net "GND")
		)
		(pad "BB24" smd circle
			(at -18.705576 -7.808468 270)
			(size 0.4318 0.4318)
			(layers "F.Cu" "F.Mask" "F.Paste")
			(net "GND")
		)
		(pad "BB26" smd circle
			(at -17.07769 -7.808468 270)
			(size 0.4318 0.4318)
			(layers "F.Cu" "F.Mask" "F.Paste")
			(net "GND")
		)
		(pad "BB61" smd circle
			(at 13.008356 -7.698486 270)
			(size 0.4318 0.4318)
			(layers "F.Cu" "F.Mask" "F.Paste")
			(net "NC_SPI_S3M_CPU1_CS0_LVC1_R_N")
		)
		(pad "BB63" smd circle
			(at 14.635988 -7.698486 270)
			(size 0.4318 0.4318)
			(layers "F.Cu" "F.Mask" "F.Paste")
			(net "GND")
		)
		(pad "BB65" smd circle
			(at 16.263874 -7.698486 270)
			(size 0.4318 0.4318)
			(layers "F.Cu" "F.Mask" "F.Paste")
			(net "PU_CPU1_UPI2_AC_COUPLING")
		)
		(pad "BB67" smd circle
			(at 17.89176 -7.698486 270)
			(size 0.4318 0.4318)
			(layers "F.Cu" "F.Mask" "F.Paste")
			(net "NC_SPI_CPU1_NCM_OE_N")
		)
		(pad "BB69" smd circle
			(at 19.519392 -7.698486 270)
			(size 0.4318 0.4318)
			(layers "F.Cu" "F.Mask" "F.Paste")
			(net "GND")
		)
		(pad "BB71" smd circle
			(at 21.147278 -7.698486 270)
			(size 0.4318 0.4318)
			(layers "F.Cu" "F.Mask" "F.Paste")
			(net "GND")
		)
		(pad "BB73" smd circle
			(at 22.77491 -7.698486 270)
			(size 0.4318 0.4318)
			(layers "F.Cu" "F.Mask" "F.Paste")
			(net "UPI_CPU0_CPU1_P2P2_DP<12>")
		)
		(pad "BB75" smd circle
			(at 24.402796 -7.698486 270)
			(size 0.4318 0.4318)
			(layers "F.Cu" "F.Mask" "F.Paste")
			(net "UPI_CPU0_CPU1_P2P2_DN<15>")
		)
		(pad "BB77" smd circle
			(at 26.030682 -7.698486 270)
			(size 0.4318 0.4318)
			(layers "F.Cu" "F.Mask" "F.Paste")
			(net "GND")
		)
		(pad "BB79" smd circle
			(at 27.658314 -7.698486 270)
			(size 0.4318 0.4318)
			(layers "F.Cu" "F.Mask" "F.Paste")
			(net "GND")
		)
		(pad "BB81" smd circle
			(at 29.2862 -7.698486 270)
			(size 0.4318 0.4318)
			(layers "F.Cu" "F.Mask" "F.Paste")
			(net "UPI_CPU1_CPU0_P2P2_DP<17>")
		)
		(pad "BB83" smd circle
			(at 30.914086 -7.698486 270)
			(size 0.4318 0.4318)
			(layers "F.Cu" "F.Mask" "F.Paste")
			(net "GND")
		)
		(pad "BB85" smd circle
			(at 32.541718 -7.698486 270)
			(size 0.4318 0.4318)
			(layers "F.Cu" "F.Mask" "F.Paste")
			(net "P5E_CPU1_PE4_TX_DP<15>")
		)
		(pad "BB87" smd circle
			(at 34.169604 -7.698486 270)
			(size 0.4318 0.4318)
			(layers "F.Cu" "F.Mask" "F.Paste")
			(net "GND")
		)
		(pad "BB89" smd circle
			(at 35.797236 -7.698486 270)
			(size 0.4318 0.4318)
			(layers "F.Cu" "F.Mask" "F.Paste")
			(net "P5E_CPU1_PE4_RX_DN<15>")
		)
		(pad "BB91" smd oval
			(at 37.425122 -7.698486)
			(size 0.381 0.4826)
			(drill
				(offset 0 -0.0508)
			)
			(layers "F.Cu" "F.Mask" "F.Paste")
			(net "GND")
		)
		(pad "BC1" smd oval
			(at -37.425122 -7.338314 180)
			(size 0.381 0.4826)
			(drill
				(offset 0 -0.0508)
			)
			(layers "F.Cu" "F.Mask" "F.Paste")
			(net "GND")
		)
		(pad "BC3" smd circle
			(at -35.797236 -7.338314 270)
			(size 0.4318 0.4318)
			(layers "F.Cu" "F.Mask" "F.Paste")
			(net "UPI_CPU1_CPU0_P0P1_DP<17>")
		)
		(pad "BC5" smd circle
			(at -34.169604 -7.338314 270)
			(size 0.4318 0.4318)
			(layers "F.Cu" "F.Mask" "F.Paste")
			(net "GND")
		)
		(pad "BC7" smd circle
			(at -32.541718 -7.338314 270)
			(size 0.4318 0.4318)
			(layers "F.Cu" "F.Mask" "F.Paste")
			(net "UPI_CPU0_CPU1_P1P0_DP<16>")
		)
		(pad "BC9" smd circle
			(at -30.914086 -7.338314 270)
			(size 0.4318 0.4318)
			(layers "F.Cu" "F.Mask" "F.Paste")
			(net "GND")
		)
		(pad "BC11" smd circle
			(at -29.2862 -7.338314 270)
			(size 0.4318 0.4318)
			(layers "F.Cu" "F.Mask" "F.Paste")
			(net "P5E_CPU1_PE1_RX_DN<15>")
		)
		(pad "BC13" smd circle
			(at -27.658314 -7.338314 270)
			(size 0.4318 0.4318)
			(layers "F.Cu" "F.Mask" "F.Paste")
			(net "GND")
		)
		(pad "BC15" smd circle
			(at -26.030682 -7.338314 270)
			(size 0.4318 0.4318)
			(layers "F.Cu" "F.Mask" "F.Paste")
			(net "P5E_CPU1_PE0_TX_DP<15>")
		)
		(pad "BC17" smd circle
			(at -24.402796 -7.338314 270)
			(size 0.4318 0.4318)
			(layers "F.Cu" "F.Mask" "F.Paste")
			(net "GND")
		)
		(pad "BC19" smd circle
			(at -22.77491 -7.338314 270)
			(size 0.4318 0.4318)
			(layers "F.Cu" "F.Mask" "F.Paste")
			(net "TP_DMI_CPU1_PCH_RX_C_DP<0>")
		)
		(pad "BC21" smd circle
			(at -21.147278 -7.338314 270)
			(size 0.4318 0.4318)
			(layers "F.Cu" "F.Mask" "F.Paste")
			(net "P3V3_AUX")
		)
		(pad "BC23" smd circle
			(at -19.519392 -7.338314 270)
			(size 0.4318 0.4318)
			(layers "F.Cu" "F.Mask" "F.Paste")
			(net "TP_CPU1_IFST_DONE_LVC1_R")
		)
		(pad "BC25" smd circle
			(at -17.89176 -7.338314 270)
			(size 0.4318 0.4318)
			(layers "F.Cu" "F.Mask" "F.Paste")
			(net "TP_I3C_MNG3_BMC_SW_SDA")
		)
		(pad "BC60" smd circle
			(at 12.19454 -7.228332 270)
			(size 0.4318 0.4318)
			(layers "F.Cu" "F.Mask" "F.Paste")
			(net "PVCCINFAON_CPU1")
		)
		(pad "BC62" smd circle
			(at 13.822426 -7.228332 270)
			(size 0.4318 0.4318)
			(layers "F.Cu" "F.Mask" "F.Paste")
			(net "GND")
		)
		(pad "BC64" smd circle
			(at 15.450058 -7.228332 270)
			(size 0.4318 0.4318)
			(layers "F.Cu" "F.Mask" "F.Paste")
			(net "NC_SPI_S3M_CPU1_CLK_LVC1_R")
		)
		(pad "BC66" smd circle
			(at 17.07769 -7.228332 270)
			(size 0.4318 0.4318)
			(layers "F.Cu" "F.Mask" "F.Paste")
			(net "GND")
		)
		(pad "BC68" smd circle
			(at 18.705576 -7.228332 270)
			(size 0.4318 0.4318)
			(layers "F.Cu" "F.Mask" "F.Paste")
			(net "TP_TRC_CPU1_PTI<21>")
		)
		(pad "BC70" smd circle
			(at 20.333462 -7.228332 270)
			(size 0.4318 0.4318)
			(layers "F.Cu" "F.Mask" "F.Paste")
			(net "TP_TRC_CPU1_PTI<16>")
		)
		(pad "BC72" smd circle
			(at 21.961094 -7.228332 270)
			(size 0.4318 0.4318)
			(layers "F.Cu" "F.Mask" "F.Paste")
			(net "GND")
		)
		(pad "BC74" smd circle
			(at 23.58898 -7.228332 270)
			(size 0.4318 0.4318)
			(layers "F.Cu" "F.Mask" "F.Paste")
			(net "UPI_CPU0_CPU1_P2P2_DP<23>")
		)
		(pad "BC76" smd circle
			(at 25.216612 -7.228332 270)
			(size 0.4318 0.4318)
			(layers "F.Cu" "F.Mask" "F.Paste")
			(net "GND")
		)
		(pad "BC78" smd circle
			(at 26.844498 -7.228332 270)
			(size 0.4318 0.4318)
			(layers "F.Cu" "F.Mask" "F.Paste")
			(net "GND")
		)
		(pad "BC80" smd circle
			(at 28.472384 -7.228332 270)
			(size 0.4318 0.4318)
			(layers "F.Cu" "F.Mask" "F.Paste")
			(net "UPI_CPU1_CPU0_P2P2_DP<20>")
		)
		(pad "BC82" smd circle
			(at 30.100016 -7.228332 270)
			(size 0.4318 0.4318)
			(layers "F.Cu" "F.Mask" "F.Paste")
			(net "UPI_CPU1_CPU0_P2P2_DN<18>")
		)
		(pad "BC84" smd circle
			(at 31.727902 -7.228332 270)
			(size 0.4318 0.4318)
			(layers "F.Cu" "F.Mask" "F.Paste")
			(net "GND")
		)
		(pad "BC86" smd circle
			(at 33.355534 -7.228332 270)
			(size 0.4318 0.4318)
			(layers "F.Cu" "F.Mask" "F.Paste")
			(net "GND")
		)
		(pad "BC88" smd circle
			(at 34.98342 -7.228332 270)
			(size 0.4318 0.4318)
			(layers "F.Cu" "F.Mask" "F.Paste")
			(net "GND")
		)
		(pad "BC90" smd circle
			(at 36.611306 -7.228332 270)
			(size 0.4318 0.4318)
			(layers "F.Cu" "F.Mask" "F.Paste")
			(net "VSENSE_PVCCIN_CPU1_DN")
		)
		(pad "BD2" smd circle
			(at -36.611306 -6.868668 270)
			(size 0.4318 0.4318)
			(layers "F.Cu" "F.Mask" "F.Paste")
			(net "UPI_CPU1_CPU0_P0P1_DN<17>")
		)
		(pad "BD4" smd circle
			(at -34.98342 -6.868668 270)
			(size 0.4318 0.4318)
			(layers "F.Cu" "F.Mask" "F.Paste")
			(net "GND")
		)
		(pad "BD6" smd circle
			(at -33.355534 -6.868668 270)
			(size 0.4318 0.4318)
			(layers "F.Cu" "F.Mask" "F.Paste")
			(net "UPI_CPU0_CPU1_P1P0_DP<17>")
		)
		(pad "BD8" smd circle
			(at -31.727902 -6.868668 270)
			(size 0.4318 0.4318)
			(layers "F.Cu" "F.Mask" "F.Paste")
			(net "GND")
		)
		(pad "BD10" smd circle
			(at -30.100016 -6.868668 270)
			(size 0.4318 0.4318)
			(layers "F.Cu" "F.Mask" "F.Paste")
			(net "P5E_CPU1_PE1_RX_DP<15>")
		)
		(pad "BD12" smd circle
			(at -28.472384 -6.868668 270)
			(size 0.4318 0.4318)
			(layers "F.Cu" "F.Mask" "F.Paste")
			(net "GND")
		)
		(pad "BD14" smd circle
			(at -26.844498 -6.868668 270)
			(size 0.4318 0.4318)
			(layers "F.Cu" "F.Mask" "F.Paste")
			(net "P5E_CPU1_PE1_TX_DP<15>")
		)
		(pad "BD16" smd circle
			(at -25.216612 -6.868668 270)
			(size 0.4318 0.4318)
			(layers "F.Cu" "F.Mask" "F.Paste")
			(net "GND")
		)
		(pad "BD18" smd circle
			(at -23.58898 -6.868668 270)
			(size 0.4318 0.4318)
			(layers "F.Cu" "F.Mask" "F.Paste")
			(net "TP_DMI_CPU1_PCH_RX_C_DP<1>")
		)
		(pad "BD20" smd circle
			(at -21.961094 -6.868668 270)
			(size 0.4318 0.4318)
			(layers "F.Cu" "F.Mask" "F.Paste")
			(net "GND")
		)
		(pad "BD22" smd circle
			(at -20.333462 -6.868668 270)
			(size 0.4318 0.4318)
			(layers "F.Cu" "F.Mask" "F.Paste")
			(net "H_CPU1_ERR2_LVC1_R_N")
		)
		(pad "BD24" smd circle
			(at -18.705576 -6.868668 270)
			(size 0.4318 0.4318)
			(layers "F.Cu" "F.Mask" "F.Paste")
			(net "H_PMAX_TRIGGER_IO_CPU1")
		)
		(pad "BD26" smd circle
			(at -17.07769 -6.868668 270)
			(size 0.4318 0.4318)
			(layers "F.Cu" "F.Mask" "F.Paste")
			(net "SVID_DIO0_CPU1")
		)
		(pad "BD61" smd circle
			(at 13.008356 -6.758686 270)
			(size 0.4318 0.4318)
			(layers "F.Cu" "F.Mask" "F.Paste")
			(net "NC_SPI_S3M_CPU1_IO3_LVC1_R")
		)
		(pad "BD63" smd circle
			(at 14.635988 -6.758686 270)
			(size 0.4318 0.4318)
			(layers "F.Cu" "F.Mask" "F.Paste")
			(net "NC_ESPI_IBL_CPU1_ALERT1_N")
		)
		(pad "BD65" smd circle
			(at 16.263874 -6.758686 270)
			(size 0.4318 0.4318)
			(layers "F.Cu" "F.Mask" "F.Paste")
			(net "NC_SPI_S3M_CPU1_IO2_LVC1_R")
		)
		(pad "BD67" smd circle
			(at 17.89176 -6.758686 270)
			(size 0.4318 0.4318)
			(layers "F.Cu" "F.Mask" "F.Paste")
			(net "TP_TRC_CPU1_PTI<23>")
		)
		(pad "BD69" smd circle
			(at 19.519392 -6.758686 270)
			(size 0.4318 0.4318)
			(layers "F.Cu" "F.Mask" "F.Paste")
			(net "TP_TRC_CPU1_PTI<18>")
		)
		(pad "BD71" smd circle
			(at 21.147278 -6.758686 270)
			(size 0.4318 0.4318)
			(layers "F.Cu" "F.Mask" "F.Paste")
			(net "NC_CPU1_MDFI_DIE01_NS1")
		)
		(pad "BD73" smd circle
			(at 22.77491 -6.758686 270)
			(size 0.4318 0.4318)
			(layers "F.Cu" "F.Mask" "F.Paste")
			(net "UPI_CPU0_CPU1_P2P2_DN<23>")
		)
		(pad "BD75" smd circle
			(at 24.402796 -6.758686 270)
			(size 0.4318 0.4318)
			(layers "F.Cu" "F.Mask" "F.Paste")
			(net "UPI_CPU0_CPU1_P2P2_DP<15>")
		)
		(pad "BD77" smd circle
			(at 26.030682 -6.758686 270)
			(size 0.4318 0.4318)
			(layers "F.Cu" "F.Mask" "F.Paste")
			(net "TP_CPU1_SPARE13")
		)
		(pad "BD79" smd circle
			(at 27.658314 -6.758686 270)
			(size 0.4318 0.4318)
			(layers "F.Cu" "F.Mask" "F.Paste")
			(net "UPI_CPU1_CPU0_P2P2_DN<20>")
		)
		(pad "BD81" smd circle
			(at 29.2862 -6.758686 270)
			(size 0.4318 0.4318)
			(layers "F.Cu" "F.Mask" "F.Paste")
			(net "GND")
		)
		(pad "BD83" smd circle
			(at 30.914086 -6.758686 270)
			(size 0.4318 0.4318)
			(layers "F.Cu" "F.Mask" "F.Paste")
			(net "UPI_CPU1_CPU0_P2P2_DP<19>")
		)
		(pad "BD85" smd circle
			(at 32.541718 -6.758686 270)
			(size 0.4318 0.4318)
			(layers "F.Cu" "F.Mask" "F.Paste")
			(net "GND")
		)
		(pad "BD87" smd circle
			(at 34.169604 -6.758686 270)
			(size 0.4318 0.4318)
			(layers "F.Cu" "F.Mask" "F.Paste")
			(net "VSENSE_PVCCIN_CPU1_DP")
		)
		(pad "BD89" smd circle
			(at 35.797236 -6.758686 270)
			(size 0.4318 0.4318)
			(layers "F.Cu" "F.Mask" "F.Paste")
			(net "GND")
		)
		(pad "BD91" smd oval
			(at 37.425122 -6.758686)
			(size 0.381 0.4826)
			(drill
				(offset 0 -0.0508)
			)
			(layers "F.Cu" "F.Mask" "F.Paste")
			(net "PVCCIN_CPU1")
		)
		(pad "BE1" smd oval
			(at -37.425122 -6.398514 180)
			(size 0.381 0.4826)
			(drill
				(offset 0 -0.0508)
			)
			(layers "F.Cu" "F.Mask" "F.Paste")
			(net "UPI_CPU1_CPU0_P0P1_DP<18>")
		)
		(pad "BE3" smd circle
			(at -35.797236 -6.398514 270)
			(size 0.4318 0.4318)
			(layers "F.Cu" "F.Mask" "F.Paste")
			(net "PVCCD_HV_CPU1")
		)
		(pad "BE5" smd circle
			(at -34.169604 -6.398514 270)
			(size 0.4318 0.4318)
			(layers "F.Cu" "F.Mask" "F.Paste")
			(net "UPI_CPU0_CPU1_P1P0_DN<17>")
		)
		(pad "BE7" smd circle
			(at -32.541718 -6.398514 270)
			(size 0.4318 0.4318)
			(layers "F.Cu" "F.Mask" "F.Paste")
			(net "PVCCD_HV_CPU1")
		)
		(pad "BE9" smd circle
			(at -30.914086 -6.398514 270)
			(size 0.4318 0.4318)
			(layers "F.Cu" "F.Mask" "F.Paste")
			(net "P5E_CPU1_PE1_RX_DP<14>")
		)
		(pad "BE11" smd circle
			(at -29.2862 -6.398514 270)
			(size 0.4318 0.4318)
			(layers "F.Cu" "F.Mask" "F.Paste")
			(net "PVCCD_HV_CPU1")
		)
		(pad "BE13" smd circle
			(at -27.658314 -6.398514 270)
			(size 0.4318 0.4318)
			(layers "F.Cu" "F.Mask" "F.Paste")
			(net "P5E_CPU1_PE1_TX_DN<15>")
		)
		(pad "BE15" smd circle
			(at -26.030682 -6.398514 270)
			(size 0.4318 0.4318)
			(layers "F.Cu" "F.Mask" "F.Paste")
			(net "PVCCINFAON_CPU1")
		)
		(pad "BE17" smd circle
			(at -24.402796 -6.398514 270)
			(size 0.4318 0.4318)
			(layers "F.Cu" "F.Mask" "F.Paste")
			(net "TP_DMI_CPU1_PCH_RX_C_DN<1>")
		)
		(pad "BE19" smd circle
			(at -22.77491 -6.398514 270)
			(size 0.4318 0.4318)
			(layers "F.Cu" "F.Mask" "F.Paste")
			(net "PVNN_MAIN_CPU1")
		)
		(pad "BE21" smd circle
			(at -21.147278 -6.398514 270)
			(size 0.4318 0.4318)
			(layers "F.Cu" "F.Mask" "F.Paste")
			(net "TP_CPU1_DIE_HVM_EN_LVC1")
		)
	)
)
